(kicad_pcb
	(version 20241229)
	(generator "pcbnew")
	(generator_version "9.0")
	(general
		(thickness 1.6296)
		(legacy_teardrops no)
	)
	(paper "A3")
	(title_block
		(title "Thunderbolt to 10GbE adapter")
		(date "2026-04-21")
		(rev "1.1.0")
		(company "Antmicro Ltd")
		(comment 1 "www.antmicro.com")
		(comment 9 "footprints 169-173 of 703")
	)
	(layers
		(0 "F.Cu" signal)
		(4 "In1.Cu" signal)
		(6 "In2.Cu" signal)
		(8 "In3.Cu" signal)
		(10 "In4.Cu" signal)
		(12 "In5.Cu" signal)
		(14 "In6.Cu" signal)
		(2 "B.Cu" signal)
		(9 "F.Adhes" user "F.Adhesive")
		(11 "B.Adhes" user "B.Adhesive")
		(13 "F.Paste" user)
		(15 "B.Paste" user)
		(5 "F.SilkS" user "F.Silkscreen")
		(7 "B.SilkS" user "B.Silkscreen")
		(1 "F.Mask" user)
		(3 "B.Mask" user)
		(17 "Dwgs.User" user "User.Drawings")
		(19 "Cmts.User" user "User.Comments")
		(21 "Eco1.User" user "User.Eco1")
		(23 "Eco2.User" user "User.Eco2")
		(25 "Edge.Cuts" user)
		(27 "Margin" user)
		(31 "F.CrtYd" user "F.Courtyard")
		(29 "B.CrtYd" user "B.Courtyard")
		(35 "F.Fab" user)
		(33 "B.Fab" user)
	)
	(footprint "antmicro-footprints:C_0402_1005Metric"
		(layer "F.Cu")
		(at 119.65 106.25 180)
		(descr "Capacitor SMD 0402")
		(tags "capacitor SMD 0402")
		(property "Reference" "C10"
			(at -6.55 -6.75 180)
			(layer "F.SilkS")
			(effects
				(font
					(size 0.7 0.7)
					(thickness 0.15)
				)
			)
		)
		(property "Value" "C_100n_0402"
			(at -1.022927 2.155213 180)
			(layer "F.Fab")
			(effects
				(font
					(size 0.7 0.7)
					(thickness 0.15)
				)
				(justify left bottom)
			)
		)
		(property "Datasheet" "https://www.murata.com/products/productdetail?partno=GRM155R61H104KE14%23"
			(at 0 0 180)
			(layer "F.Fab")
			(hide yes)
			(effects
				(font
					(size 1.27 1.27)
					(thickness 0.15)
				)
			)
		)
		(property "Description" "SMD Multilayer Ceramic Capacitor, 0.1 µF, 50 V, 0402 [1005 Metric], ± 10%, X5R, GRM Series"
			(at 0 0 180)
			(layer "F.Fab")
			(hide yes)
			(effects
				(font
					(size 1.27 1.27)
					(thickness 0.15)
				)
			)
		)
		(property "MPN" "GRM155R61H104KE14D"
			(at 0 0 180)
			(unlocked yes)
			(layer "F.Fab")
			(hide yes)
			(effects
				(font
					(size 1 1)
					(thickness 0.15)
				)
			)
		)
		(property "Manufacturer" "Murata"
			(at 0 0 180)
			(unlocked yes)
			(layer "F.Fab")
			(hide yes)
			(effects
				(font
					(size 1 1)
					(thickness 0.15)
				)
			)
		)
		(property "License" "Apache-2.0"
			(at 0 0 180)
			(unlocked yes)
			(layer "F.Fab")
			(hide yes)
			(effects
				(font
					(size 1 1)
					(thickness 0.15)
				)
			)
		)
		(property "Val" "100n"
			(at 0 0 180)
			(unlocked yes)
			(layer "F.Fab")
			(hide yes)
			(effects
				(font
					(size 1 1)
					(thickness 0.15)
				)
			)
		)
		(property "Voltage" "50V"
			(at 0 0 180)
			(unlocked yes)
			(layer "F.Fab")
			(hide yes)
			(effects
				(font
					(size 1 1)
					(thickness 0.15)
				)
			)
		)
		(property "Dielectric" "X5R"
			(at 0 0 180)
			(unlocked yes)
			(layer "F.Fab")
			(hide yes)
			(effects
				(font
					(size 1 1)
					(thickness 0.15)
				)
			)
		)
		(property "Author" "Antmicro"
			(at 0 0 180)
			(unlocked yes)
			(layer "F.Fab")
			(hide yes)
			(effects
				(font
					(size 1 1)
					(thickness 0.15)
				)
			)
		)
		(sheetname "/PD and TB DC-DC/")
		(sheetfile "PD_and_TB_DC_DC.kicad_sch")
		(attr smd)
		(fp_rect
			(start -0.925 -0.47)
			(end 0.925 0.47)
			(stroke
				(width 0.05)
				(type default)
			)
			(fill no)
			(layer "F.CrtYd")
		)
		(fp_line
			(start 0.504 0.248)
			(end -0.494 0.248)
			(stroke
				(width 0.15)
				(type solid)
			)
			(layer "F.Fab")
		)
		(fp_line
			(start 0.504 -0.25)
			(end 0.504 0.248)
			(stroke
				(width 0.15)
				(type solid)
			)
			(layer "F.Fab")
		)
		(fp_line
			(start -0.494 0.248)
			(end -0.494 -0.25)
			(stroke
				(width 0.15)
				(type solid)
			)
			(layer "F.Fab")
		)
		(fp_line
			(start -0.494 -0.25)
			(end 0.504 -0.25)
			(stroke
				(width 0.15)
				(type solid)
			)
			(layer "F.Fab")
		)
		(fp_text user "License: Apache-2.0"
			(at -0.939 5.799 180)
			(layer "F.Fab")
			(effects
				(font
					(size 0.7 0.7)
					(thickness 0.15)
				)
				(justify left bottom)
			)
		)
		(fp_text user "${REFERENCE}"
			(at -0.939 4.599 180)
			(layer "F.Fab")
			(effects
				(font
					(size 0.7 0.7)
					(thickness 0.15)
				)
				(justify left bottom)
			)
		)
		(fp_text user "Author: Antmicro"
			(at -0.939 3.399 180)
			(layer "F.Fab")
			(effects
				(font
					(size 0.7 0.7)
					(thickness 0.15)
				)
				(justify left bottom)
			)
		)
		(pad "1" smd roundrect
			(at -0.48 0 180)
			(size 0.59 0.64)
			(layers "F.Cu" "F.Mask" "F.Paste")
			(roundrect_rratio 0.25)
			(net 23 "GND")
			(pintype "passive")
		)
		(pad "2" smd roundrect
			(at 0.48 0 180)
			(size 0.59 0.64)
			(layers "F.Cu" "F.Mask" "F.Paste")
			(roundrect_rratio 0.25)
			(net 161 "Net-(U2-VIN)")
			(pintype "passive")
		)
	)
	(footprint "antmicro-footprints:R_0402_1005Metric"
		(layer "F.Cu")
		(at 136.149999 112.150001)
		(descr "Resistor SMD 0402")
		(tags "resistor SMD 0402")
		(property "Reference" "R101"
			(at 16.549997 17.25 0)
			(layer "F.SilkS")
			(effects
				(font
					(size 0.7 0.7)
					(thickness 0.15)
				)
			)
		)
		(property "Value" "R_30k_0402"
			(at -1.011843 1.772047 0)
			(layer "F.Fab")
			(effects
				(font
					(size 0.7 0.7)
					(thickness 0.15)
				)
				(justify left bottom)
			)
		)
		(property "Datasheet" "https://www.bourns.com/docs/product-datasheets/cr.pdf"
			(at 0 0 0)
			(layer "F.Fab")
			(hide yes)
			(effects
				(font
					(size 1.27 1.27)
					(thickness 0.15)
				)
			)
		)
		(property "Description" "SMD Chip Resistor, 30 kohm, ± 1%, 63 mW, 0402 [1005 Metric], Thick Film, General Purpose"
			(at 0 0 0)
			(layer "F.Fab")
			(hide yes)
			(effects
				(font
					(size 1.27 1.27)
					(thickness 0.15)
				)
			)
		)
		(property "MPN" "CR0402-FX-3002GLF"
			(at 0 0 0)
			(unlocked yes)
			(layer "F.Fab")
			(hide yes)
			(effects
				(font
					(size 1 1)
					(thickness 0.15)
				)
			)
		)
		(property "Manufacturer" "Bourns"
			(at 0 0 0)
			(unlocked yes)
			(layer "F.Fab")
			(hide yes)
			(effects
				(font
					(size 1 1)
					(thickness 0.15)
				)
			)
		)
		(property "License" "Apache-2.0"
			(at 0 0 0)
			(unlocked yes)
			(layer "F.Fab")
			(hide yes)
			(effects
				(font
					(size 1 1)
					(thickness 0.15)
				)
			)
		)
		(property "Author" "Antmicro"
			(at 0 0 0)
			(unlocked yes)
			(layer "F.Fab")
			(hide yes)
			(effects
				(font
					(size 1 1)
					(thickness 0.15)
				)
			)
		)
		(property "Val" "30k"
			(at 0 0 0)
			(unlocked yes)
			(layer "F.Fab")
			(hide yes)
			(effects
				(font
					(size 1 1)
					(thickness 0.15)
				)
			)
		)
		(property "Tolerance" "1%"
			(at 0 0 0)
			(unlocked yes)
			(layer "F.Fab")
			(hide yes)
			(effects
				(font
					(size 1 1)
					(thickness 0.15)
				)
			)
		)
		(sheetname "/X710 DCDC converters/")
		(sheetfile "DCDC_converters_X710.kicad_sch")
		(attr smd)
		(fp_rect
			(start -0.925 -0.47)
			(end 0.925 0.47)
			(stroke
				(width 0.05)
				(type default)
			)
			(fill no)
			(layer "F.CrtYd")
		)
		(fp_rect
			(start -0.5 -0.25)
			(end 0.5 0.25)
			(stroke
				(width 0.15)
				(type solid)
			)
			(fill no)
			(layer "F.Fab")
		)
		(fp_text user "Author: Antmicro"
			(at -0.95 4.169 0)
			(layer "F.Fab")
			(effects
				(font
					(size 0.7 0.7)
					(thickness 0.15)
				)
				(justify left bottom)
			)
		)
		(fp_text user "License: Apache-2.0"
			(at -0.95 5.169 0)
			(layer "F.Fab")
			(effects
				(font
					(size 0.7 0.7)
					(thickness 0.15)
				)
				(justify left bottom)
			)
		)
		(fp_text user "${REFERENCE}"
			(at -0.95 3.168 0)
			(layer "F.Fab")
			(effects
				(font
					(size 0.7 0.7)
					(thickness 0.15)
				)
				(justify left bottom)
			)
		)
		(pad "1" smd roundrect
			(at -0.48 0)
			(size 0.59 0.64)
			(layers "F.Cu" "F.Mask" "F.Paste")
			(roundrect_rratio 0.25)
			(net 23 "GND")
			(pintype "passive")
		)
		(pad "2" smd roundrect
			(at 0.48 0)
			(size 0.59 0.64)
			(layers "F.Cu" "F.Mask" "F.Paste")
			(roundrect_rratio 0.25)
			(net 336 "/X710 DCDC converters/VCCD_FB")
			(pintype "passive")
		)
	)
	(footprint "antmicro-footprints:R_0402_1005Metric"
		(layer "F.Cu")
		(at 117 69.9 180)
		(descr "Resistor SMD 0402")
		(tags "resistor SMD 0402")
		(property "Reference" "R218"
			(at -3.6 10.5 180)
			(layer "F.SilkS")
			(effects
				(font
					(size 0.7 0.7)
					(thickness 0.15)
				)
				(justify left bottom)
			)
		)
		(property "Value" "R_10k_0402"
			(at -1.011843 1.772047 180)
			(layer "F.Fab")
			(effects
				(font
					(size 0.7 0.7)
					(thickness 0.15)
				)
				(justify left bottom)
			)
		)
		(property "Datasheet" "https://www.bourns.com/docs/product-datasheets/cr.pdf"
			(at 0 0 180)
			(layer "F.Fab")
			(hide yes)
			(effects
				(font
					(size 1.27 1.27)
					(thickness 0.15)
				)
			)
		)
		(property "Description" "SMD Chip Resistor, 10 kohm, ± 1%, 62.5 mW, 0402 [1005 Metric], Thick Film, General Purpose"
			(at 0 0 180)
			(layer "F.Fab")
			(hide yes)
			(effects
				(font
					(size 1.27 1.27)
					(thickness 0.15)
				)
			)
		)
		(property "MPN" "CR0402-FX-1002GLF"
			(at 0 0 180)
			(unlocked yes)
			(layer "F.Fab")
			(hide yes)
			(effects
				(font
					(size 1 1)
					(thickness 0.15)
				)
			)
		)
		(property "Manufacturer" "Bourns"
			(at 0 0 180)
			(unlocked yes)
			(layer "F.Fab")
			(hide yes)
			(effects
				(font
					(size 1 1)
					(thickness 0.15)
				)
			)
		)
		(property "License" "Apache-2.0"
			(at 0 0 180)
			(unlocked yes)
			(layer "F.Fab")
			(hide yes)
			(effects
				(font
					(size 1 1)
					(thickness 0.15)
				)
			)
		)
		(property "Author" "Antmicro"
			(at 0 0 180)
			(unlocked yes)
			(layer "F.Fab")
			(hide yes)
			(effects
				(font
					(size 1 1)
					(thickness 0.15)
				)
			)
		)
		(property "Val" "10k"
			(at 0 0 180)
			(unlocked yes)
			(layer "F.Fab")
			(hide yes)
			(effects
				(font
					(size 1 1)
					(thickness 0.15)
				)
			)
		)
		(property "Tolerance" "1%"
			(at 0 0 180)
			(unlocked yes)
			(layer "F.Fab")
			(hide yes)
			(effects
				(font
					(size 1 1)
					(thickness 0.15)
				)
			)
		)
		(sheetname "/Fan controller/")
		(sheetfile "fan-controller.kicad_sch")
		(attr smd)
		(fp_rect
			(start -0.925 -0.47)
			(end 0.925 0.47)
			(stroke
				(width 0.05)
				(type default)
			)
			(fill no)
			(layer "F.CrtYd")
		)
		(fp_rect
			(start -0.5 -0.25)
			(end 0.5 0.25)
			(stroke
				(width 0.15)
				(type solid)
			)
			(fill no)
			(layer "F.Fab")
		)
		(fp_text user "${REFERENCE}"
			(at -0.95 3.168 180)
			(layer "F.Fab")
			(effects
				(font
					(size 0.7 0.7)
					(thickness 0.15)
				)
				(justify left bottom)
			)
		)
		(fp_text user "License: Apache-2.0"
			(at -0.95 5.169 180)
			(layer "F.Fab")
			(effects
				(font
					(size 0.7 0.7)
					(thickness 0.15)
				)
				(justify left bottom)
			)
		)
		(fp_text user "Author: Antmicro"
			(at -0.95 4.169 180)
			(layer "F.Fab")
			(effects
				(font
					(size 0.7 0.7)
					(thickness 0.15)
				)
				(justify left bottom)
			)
		)
		(pad "1" smd roundrect
			(at -0.48 0 180)
			(size 0.59 0.64)
			(layers "F.Cu" "F.Mask" "F.Paste")
			(roundrect_rratio 0.25)
			(net 157 "/Fan controller/DMIN")
			(pintype "passive")
		)
		(pad "2" smd roundrect
			(at 0.48 0 180)
			(size 0.59 0.64)
			(layers "F.Cu" "F.Mask" "F.Paste")
			(roundrect_rratio 0.25)
			(net 40 "+5V")
			(pintype "passive")
		)
	)
	(footprint "antmicro-footprints:VQFN-HR-9_2x1.5mm"
		(layer "F.Cu")
		(at 139.049999 110.149999)
		(property "Reference" "U10"
			(at 16 17.049998 0)
			(layer "F.SilkS")
			(effects
				(font
					(size 0.7 0.7)
					(thickness 0.15)
				)
			)
		)
		(property "Value" "TPS566231P"
			(at -1.65 2.15 0)
			(layer "F.Fab")
			(effects
				(font
					(size 0.7 0.7)
					(thickness 0.15)
				)
				(justify left bottom)
			)
		)
		(property "Datasheet" "https://www.ti.com/lit/ds/symlink/tps566231.pdf"
			(at 0 -0.045 0)
			(layer "F.Fab")
			(effects
				(font
					(size 0.7 0.7)
					(thickness 0.15)
				)
				(justify left bottom)
			)
		)
		(property "Description" "Switching Voltage Regulators 3-V to 18-V, 6-A synchronous buck converter"
			(at -1.45 3.65 0)
			(layer "F.Fab")
			(effects
				(font
					(size 0.7 0.7)
					(thickness 0.15)
				)
				(justify left bottom)
			)
		)
		(property "Manufacturer" "Texas Instruments"
			(at 0 0 0)
			(unlocked yes)
			(layer "F.Fab")
			(hide yes)
			(effects
				(font
					(size 1 1)
					(thickness 0.15)
				)
			)
		)
		(property "MPN" "TPS566231PRQFR"
			(at 0 0 0)
			(unlocked yes)
			(layer "F.Fab")
			(hide yes)
			(effects
				(font
					(size 1 1)
					(thickness 0.15)
				)
			)
		)
		(property "Author" "Antmicro"
			(at 0 0 0)
			(unlocked yes)
			(layer "F.Fab")
			(hide yes)
			(effects
				(font
					(size 1 1)
					(thickness 0.15)
				)
			)
		)
		(property "License" "Apache-2.0"
			(at 0 0 0)
			(unlocked yes)
			(layer "F.Fab")
			(hide yes)
			(effects
				(font
					(size 1 1)
					(thickness 0.15)
				)
			)
		)
		(sheetname "/X710 DCDC converters/")
		(sheetfile "DCDC_converters_X710.kicad_sch")
		(attr smd)
		(fp_line
			(start -1 -0.945)
			(end -0.695 -0.945)
			(stroke
				(width 0.15)
				(type solid)
			)
			(layer "F.SilkS")
		)
		(fp_line
			(start -1 0.945)
			(end -0.695 0.945)
			(stroke
				(width 0.15)
				(type solid)
			)
			(layer "F.SilkS")
		)
		(fp_line
			(start 1 -0.945)
			(end 0.695 -0.945)
			(stroke
				(width 0.15)
				(type solid)
			)
			(layer "F.SilkS")
		)
		(fp_line
			(start 1 0.945)
			(end 0.2 0.945)
			(stroke
				(width 0.15)
				(type solid)
			)
			(layer "F.SilkS")
		)
		(fp_circle
			(center -1.18 -0.77)
			(end -1.13 -0.77)
			(stroke
				(width 0.15)
				(type solid)
			)
			(fill yes)
			(layer "F.SilkS")
		)
		(fp_rect
			(start -1.3 -1.05)
			(end 1.3 1.05)
			(stroke
				(width 0.05)
				(type solid)
			)
			(fill no)
			(layer "F.CrtYd")
		)
		(fp_rect
			(start -1 -0.75)
			(end 1 0.75)
			(stroke
				(width 0.15)
				(type solid)
			)
			(fill no)
			(layer "F.Fab")
		)
		(fp_text user "${REFERENCE}"
			(at -1.65 3.35 0)
			(layer "F.Fab")
			(effects
				(font
					(size 0.7 0.7)
					(thickness 0.15)
				)
				(justify left bottom)
			)
		)
		(fp_text user "Author: Antmicro"
			(at -1.65 4.55 0)
			(layer "F.Fab")
			(effects
				(font
					(size 0.7 0.7)
					(thickness 0.15)
				)
				(justify left bottom)
			)
		)
		(fp_text user "License: Apache-2.0"
			(at -1.65 5.75 0)
			(layer "F.Fab")
			(effects
				(font
					(size 0.7 0.7)
					(thickness 0.15)
				)
				(justify left bottom)
			)
		)
		(pad "1" smd roundrect
			(at -0.925 -0.5)
			(size 0.55 0.25)
			(layers "F.Cu" "F.Mask" "F.Paste")
			(roundrect_rratio 0.125)
			(net 83 "/X710 DCDC converters/VCCD_VCC")
			(pinfunction "V_{CC}")
			(pintype "passive")
		)
		(pad "2" smd roundrect
			(at -0.925 0)
			(size 0.55 0.25)
			(layers "F.Cu" "F.Mask" "F.Paste")
			(roundrect_rratio 0.125)
			(net 336 "/X710 DCDC converters/VCCD_FB")
			(pinfunction "FB")
			(pintype "input")
		)
		(pad "3" smd roundrect
			(at -0.925 0.5)
			(size 0.55 0.25)
			(layers "F.Cu" "F.Mask" "F.Paste")
			(roundrect_rratio 0.125)
			(net 382 "/X710 DCDC converters/VCCD_EN")
			(pinfunction "EN")
			(pintype "input")
		)
		(pad "4" smd roundrect
			(at -0.25 0.45)
			(size 0.25 1)
			(layers "F.Cu" "F.Mask" "F.Paste")
			(roundrect_rratio 0.125)
			(net 23 "GND")
			(pinfunction "PGND")
			(pintype "power_in")
		)
		(pad "5" smd roundrect
			(at 0.925 0.5)
			(size 0.55 0.25)
			(layers "F.Cu" "F.Mask" "F.Paste")
			(roundrect_rratio 0.125)
			(net 40 "+5V")
			(pinfunction "V_{IN}")
			(pintype "power_in")
		)
		(pad "6" smd roundrect
			(at 0.925 0)
			(size 0.55 0.25)
			(layers "F.Cu" "F.Mask" "F.Paste")
			(roundrect_rratio 0.125)
			(net 40 "+5V")
			(pinfunction "V_{IN}")
			(pintype "passive")
		)
		(pad "7" smd roundrect
			(at 0.925 -0.5)
			(size 0.55 0.25)
			(layers "F.Cu" "F.Mask" "F.Paste")
			(roundrect_rratio 0.125)
			(net 119 "/X710 DCDC converters/VCCD_BST")
			(pinfunction "BST")
			(pintype "passive")
		)
		(pad "8" smd roundrect
			(at 0.25 -0.3)
			(size 0.25 1.3)
			(layers "F.Cu" "F.Mask" "F.Paste")
			(roundrect_rratio 0.125)
			(net 153 "/X710 DCDC converters/VCCD_SW")
			(pinfunction "SW")
			(pintype "power_out")
		)
		(pad "9" smd roundrect
			(at -0.25 -0.675)
			(size 0.25 0.55)
			(layers "F.Cu" "F.Mask" "F.Paste")
			(roundrect_rratio 0.125)
			(net 379 "/X710 DCDC converters/VCCD_PG")
			(pinfunction "PG")
			(pintype "passive")
		)
	)
	(footprint "antmicro-footprints:C_0603_1608Metric"
		(layer "F.Cu")
		(at 150.305 68.574999 -90)
		(descr "Capacitor SMD 0603")
		(tags "capacitor 0603")
		(property "Reference" "C220"
			(at -12.274999 -20.045 270)
			(layer "F.SilkS")
			(effects
				(font
					(size 0.7 0.7)
					(thickness 0.15)
				)
			)
		)
		(property "Value" "C_10u_10V_X7R_0603"
			(at -1.42757 1.770288 270)
			(layer "F.Fab")
			(effects
				(font
					(size 0.7 0.7)
					(thickness 0.15)
				)
				(justify left bottom)
			)
		)
		(property "Datasheet" "https://www.murata.com/products/productdetail?partno=GRM188Z71A106KA73%23"
			(at 0 0 270)
			(layer "F.Fab")
			(hide yes)
			(effects
				(font
					(size 1.27 1.27)
					(thickness 0.15)
				)
			)
		)
		(property "Description" "SMD Multilayer Ceramic Capacitor,  10µF, 10V, 0603, ±10%, X7R"
			(at 0 0 270)
			(layer "F.Fab")
			(hide yes)
			(effects
				(font
					(size 1.27 1.27)
					(thickness 0.15)
				)
			)
		)
		(property "MPN" "GRM188Z71A106KA73D"
			(at 0 0 270)
			(unlocked yes)
			(layer "F.Fab")
			(hide yes)
			(effects
				(font
					(size 1 1)
					(thickness 0.15)
				)
			)
		)
		(property "Val" "10u"
			(at 0 0 270)
			(unlocked yes)
			(layer "F.Fab")
			(hide yes)
			(effects
				(font
					(size 1 1)
					(thickness 0.15)
				)
			)
		)
		(property "Voltage" "10V"
			(at 0 0 270)
			(unlocked yes)
			(layer "F.Fab")
			(hide yes)
			(effects
				(font
					(size 1 1)
					(thickness 0.15)
				)
			)
		)
		(property "Dielectric" "X7R"
			(at 0 0 270)
			(unlocked yes)
			(layer "F.Fab")
			(hide yes)
			(effects
				(font
					(size 1 1)
					(thickness 0.15)
				)
			)
		)
		(property "Manufacturer" "Murata"
			(at 0 0 270)
			(unlocked yes)
			(layer "F.Fab")
			(hide yes)
			(effects
				(font
					(size 1 1)
					(thickness 0.15)
				)
			)
		)
		(property "License" "Apache-2.0"
			(at 0 0 270)
			(unlocked yes)
			(layer "F.Fab")
			(hide yes)
			(effects
				(font
					(size 1 1)
					(thickness 0.15)
				)
			)
		)
		(property "Author" "Antmicro"
			(at 0 0 270)
			(unlocked yes)
			(layer "F.Fab")
			(hide yes)
			(effects
				(font
					(size 1 1)
					(thickness 0.15)
				)
			)
		)
		(sheetname "/X710-AT2 power/")
		(sheetfile "x710-at2-power.kicad_sch")
		(attr smd)
		(fp_line
			(start -0.15 0.4)
			(end 0.15 0.4)
			(stroke
				(width 0.15)
				(type solid)
			)
			(layer "F.SilkS")
		)
		(fp_line
			(start -0.15 -0.4)
			(end 0.15 -0.4)
			(stroke
				(width 0.15)
				(type solid)
			)
			(layer "F.SilkS")
		)
		(fp_rect
			(start -1.25 -0.65)
			(end 1.25 0.65)
			(stroke
				(width 0.05)
				(type solid)
			)
			(fill no)
			(layer "F.CrtYd")
		)
		(fp_rect
			(start -0.8 -0.4)
			(end 0.8 0.4)
			(stroke
				(width 0.15)
				(type solid)
			)
			(fill no)
			(layer "F.Fab")
		)
		(fp_text user "Author: Antmicro"
			(at -1.682 4.894 270)
			(layer "F.Fab")
			(effects
				(font
					(size 0.7 0.7)
					(thickness 0.15)
				)
				(justify left bottom)
			)
		)
		(fp_text user "${REFERENCE}"
			(at -1.682 3.895 270)
			(layer "F.Fab")
			(effects
				(font
					(size 0.7 0.7)
					(thickness 0.15)
				)
				(justify left bottom)
			)
		)
		(fp_text user "License: Apache-2.0"
			(at -1.682 5.895 270)
			(layer "F.Fab")
			(effects
				(font
					(size 0.7 0.7)
					(thickness 0.15)
				)
				(justify left bottom)
			)
		)
		(pad "1" smd roundrect
			(at -0.7 0 270)
			(size 0.8 1)
			(layers "F.Cu" "F.Mask" "F.Paste")
			(roundrect_rratio 0.2)
			(net 23 "GND")
			(pintype "passive")
		)
		(pad "2" smd roundrect
			(at 0.7 0 270)
			(size 0.8 1)
			(layers "F.Cu" "F.Mask" "F.Paste")
			(roundrect_rratio 0.2)
			(net 7 "+3V3")
			(pintype "passive")
		)
	)
)
